(kicad_pcb
	(version 20221018)
	(generator pcbnew)
	(general
    (thickness 1.518)
  )
	(paper "A4")
	(title_block
    (title "Kria K26 Devboard")
    (date "2024-03-26")
    (rev "1.2.5")
    (comment 1 "www.antmicro.com")
    (comment 2 "Antmicro Ltd.")
		(comment 9 "footprints 565-571 of 660")
	)
	(layers
    (0 "F.Cu" mixed)
    (1 "In1.Cu" power)
    (2 "In2.Cu" mixed)
    (3 "In3.Cu" power)
    (4 "In4.Cu" mixed)
    (5 "In5.Cu" power)
    (6 "In6.Cu" mixed)
    (31 "B.Cu" power)
    (32 "B.Adhes" user "B.Adhesive")
    (33 "F.Adhes" user "F.Adhesive")
    (34 "B.Paste" user)
    (35 "F.Paste" user)
    (36 "B.SilkS" user "B.Silkscreen")
    (37 "F.SilkS" user "F.Silkscreen")
    (38 "B.Mask" user)
    (39 "F.Mask" user)
    (40 "Dwgs.User" user "User.Drawings")
    (41 "Cmts.User" user "User.Comments")
    (42 "Eco1.User" user "User.Eco1")
    (43 "Eco2.User" user "User.Eco2")
    (44 "Edge.Cuts" user)
    (45 "Margin" user)
    (46 "B.CrtYd" user "B.Courtyard")
    (47 "F.CrtYd" user "F.Courtyard")
    (48 "B.Fab" user)
    (49 "F.Fab" user)
  )
	(footprint "kria-k26-devboard-footprints:C_0402_1005Metric" (layer "B.Cu")
    (at 147.45 85.765 -90)
    (descr "Capacitor SMD 0402")
    (tags "capacitor SMD 0402")
    (property "Author" "Antmicro")
    (property "Dielectric" "X5R")
    (property "License" "Apache-2.0")
    (property "MPN" "GRM155R61H104KE14D")
    (property "Manufacturer" "Murata")
    (property "Sheetfile" "eth.kicad_sch")
    (property "Sheetname" "Ethernet")
    (property "Val" "100n")
    (property "Voltage" "50V")
    (property "ki_description" " ")
    (attr smd)
    (fp_text reference "C102" (at -3.712385 -0.37 90) (layer "B.SilkS")
        (effects (font (size 0.7 0.7) (thickness 0.15)) (justify left bottom mirror))
    )
    (fp_text value "C_100n_0402" (at 0 -1.4 90) (layer "B.Fab") hide
        (effects (font (size 0.7 0.7) (thickness 0.15)) (justify left bottom mirror))
    )
    (fp_text user "Author: Antmicro" (at -0.932 -4.17 90) (layer "B.Fab") hide
        (effects (font (size 0.7 0.7) (thickness 0.15)) (justify left bottom mirror))
    )
    (fp_text user "${REFERENCE}" (at -0.932 -3.168 90) (layer "B.Fab") hide
        (effects (font (size 0.7 0.7) (thickness 0.15)) (justify left bottom mirror))
    )
    (fp_text user "License: Apache-2.0" (at -0.932 -5.17 90) (layer "B.Fab") hide
        (effects (font (size 0.7 0.7) (thickness 0.15)) (justify left bottom mirror))
    )
    (fp_rect (start -0.94 0.47) (end 0.94 -0.47)
      (stroke (width 0.05) (type solid)) (fill none) (layer "B.CrtYd"))
    (fp_rect (start -0.499 0.249) (end 0.499 -0.249)
      (stroke (width 0.15) (type solid)) (fill none) (layer "B.Fab"))
    (pad "1" smd roundrect (at -0.484 0 270) (size 0.59 0.64) (layers "B.Cu" "B.Paste" "B.Mask") (roundrect_rratio 0.25)
      (net 16 "PS_2V5") (pintype "passive"))
    (pad "2" smd roundrect (at 0.484 0 270) (size 0.59 0.64) (layers "B.Cu" "B.Paste" "B.Mask") (roundrect_rratio 0.25)
      (net 1 "GND") (pintype "passive"))
  )
	(footprint "kria-k26-devboard-footprints:R_0402_1005Metric" (layer "B.Cu")
    (at 154.615255 93.65 180)
    (descr "Resistor SMD 0402")
    (tags "resistor SMD 0402")
    (property "Author" "Antmicro")
    (property "License" "Apache-2.0")
    (property "MPN" "CR0402-FX-5761GLF")
    (property "Manufacturer" "Bourns")
    (property "Sheetfile" "eth.kicad_sch")
    (property "Sheetname" "Ethernet")
    (property "Tolerance" "1%")
    (property "Val" "5k76")
    (property "ki_description" "5k76 resistor in 0402 package with 1% tolerance")
    (attr smd)
    (fp_text reference "R69" (at -3.034745 -0.37) (layer "B.SilkS")
        (effects (font (size 0.7 0.7) (thickness 0.15)) (justify left bottom mirror))
    )
    (fp_text value "R_5k76_0402" (at 0 -1.4) (layer "B.Fab") hide
        (effects (font (size 0.7 0.7) (thickness 0.15)) (justify left bottom mirror))
    )
    (fp_text user "License: Apache-2.0" (at -0.95 -5.169) (layer "B.Fab") hide
        (effects (font (size 0.7 0.7) (thickness 0.15)) (justify left bottom mirror))
    )
    (fp_text user "Author: Antmicro" (at -0.95 -4.169) (layer "B.Fab") hide
        (effects (font (size 0.7 0.7) (thickness 0.15)) (justify left bottom mirror))
    )
    (fp_text user "${REFERENCE}" (at -0.95 -3.168) (layer "B.Fab") hide
        (effects (font (size 0.7 0.7) (thickness 0.15)) (justify left bottom mirror))
    )
    (fp_rect (start -0.93 0.47) (end 0.93 -0.47)
      (stroke (width 0.05) (type solid)) (fill none) (layer "B.CrtYd"))
    (fp_rect (start -0.5 0.25) (end 0.5 -0.25)
      (stroke (width 0.15) (type solid)) (fill none) (layer "B.Fab"))
    (pad "1" smd roundrect (at -0.485 0 180) (size 0.59 0.64) (layers "B.Cu" "B.Paste" "B.Mask") (roundrect_rratio 0.25)
      (net 17 "PS_1V8") (pintype "passive"))
    (pad "2" smd roundrect (at 0.485 0 180) (size 0.59 0.64) (layers "B.Cu" "B.Paste" "B.Mask") (roundrect_rratio 0.25)
      (net 28 "/Ethernet/MIO75") (pintype "passive"))
  )
	(footprint "kria-k26-devboard-footprints:SOT-563" (layer "B.Cu")
    (at 135.103449 74.171573 90)
    (property "Author" "Antmicro")
    (property "License" "Apache-2.0")
    (property "MPN" "82400152")
    (property "Manufacturer" "Würth Elektronik")
    (property "Sheetfile" "usb.kicad_sch")
    (property "Sheetname" "USB")
    (property "ki_description" "TVS diode")
    (property "ki_keywords" "SMT, DIODE, IC, ESD, TVS")
    (attr smd)
    (fp_text reference "U20" (at -0.298427 1.056551 180) (layer "B.SilkS")
        (effects (font (size 0.7 0.7) (thickness 0.15)) (justify right bottom mirror))
    )
    (fp_text value "82400152" (at 0 -2 90) (layer "B.Fab") hide
        (effects (font (size 0.7 0.7) (thickness 0.15)) (justify right bottom mirror))
    )
    (fp_text user "${REFERENCE}" (at -1.299 -7.323 90) (layer "B.Fab") hide
        (effects (font (size 0.7 0.7) (thickness 0.15)) (justify right bottom mirror))
    )
    (fp_text user "License: Apache-2.0" (at -1.299 -4.924 90) (layer "B.Fab") hide
        (effects (font (size 0.7 0.7) (thickness 0.15)) (justify right bottom mirror))
    )
    (fp_text user "Author: Antmicro" (at -1.299 -6.124 90) (layer "B.Fab") hide
        (effects (font (size 0.7 0.7) (thickness 0.15)) (justify right bottom mirror))
    )
    (fp_line (start -0.778 -0.949) (end -0.424 -0.949)
      (stroke (width 0.15) (type solid)) (layer "B.SilkS"))
    (fp_line (start -0.778 -0.776) (end -0.778 -0.949)
      (stroke (width 0.15) (type solid)) (layer "B.SilkS"))
    (fp_line (start -0.499 0.974) (end -0.724 0.778)
      (stroke (width 0.15) (type solid)) (layer "B.SilkS"))
    (fp_line (start 0.776 -0.972) (end 0.526 -0.972)
      (stroke (width 0.15) (type solid)) (layer "B.SilkS"))
    (fp_line (start 0.776 -0.776) (end 0.776 -0.972)
      (stroke (width 0.15) (type solid)) (layer "B.SilkS"))
    (fp_line (start 0.776 0.974) (end 0.526 0.974)
      (stroke (width 0.15) (type solid)) (layer "B.SilkS"))
    (fp_line (start 0.776 0.974) (end 0.776 0.778)
      (stroke (width 0.15) (type solid)) (layer "B.SilkS"))
    (fp_circle (center -0.903 0.999) (end -0.952 0.95)
      (stroke (width 0.15) (type solid)) (fill solid) (layer "B.SilkS"))
    (fp_rect (start 1.19 1.12) (end -1.2 -1.1)
      (stroke (width 0.05) (type solid)) (fill none) (layer "B.CrtYd"))
    (fp_line (start -0.653 0.678) (end -0.653 -0.847)
      (stroke (width 0.15) (type solid)) (layer "B.Fab"))
    (fp_line (start -0.453 0.849) (end -0.653 0.678)
      (stroke (width 0.15) (type solid)) (layer "B.Fab"))
    (fp_line (start -0.453 0.849) (end 0.651 0.849)
      (stroke (width 0.15) (type solid)) (layer "B.Fab"))
    (fp_line (start 0.651 -0.847) (end -0.653 -0.847)
      (stroke (width 0.15) (type solid)) (layer "B.Fab"))
    (fp_line (start 0.651 0.849) (end 0.651 -0.847)
      (stroke (width 0.15) (type solid)) (layer "B.Fab"))
    (pad "1" smd roundrect (at -0.749 0.499 180) (size 0.3 0.6) (layers "B.Cu" "B.Paste" "B.Mask") (roundrect_rratio 0.25)
      (net 67 "/USB/USB1_N") (pintype "passive"))
    (pad "2" smd roundrect (at -0.749 -0.001 180) (size 0.3 0.6) (layers "B.Cu" "B.Paste" "B.Mask") (roundrect_rratio 0.25)
      (net 1 "GND") (pintype "passive"))
    (pad "3" smd roundrect (at -0.749 -0.497 180) (size 0.3 0.6) (layers "B.Cu" "B.Paste" "B.Mask") (roundrect_rratio 0.25)
      (net 68 "/USB/USB1_P") (pintype "passive"))
    (pad "4" smd roundrect (at 0.747 -0.497 180) (size 0.3 0.6) (layers "B.Cu" "B.Paste" "B.Mask") (roundrect_rratio 0.25)
      (net 287 "/USB/USB1_TVS_P") (pintype "passive"))
    (pad "5" smd roundrect (at 0.747 -0.001 180) (size 0.3 0.6) (layers "B.Cu" "B.Paste" "B.Mask") (roundrect_rratio 0.25)
      (net 64 "/USB/USB1_VBUS") (pintype "passive"))
    (pad "6" smd roundrect (at 0.747 0.499 180) (size 0.3 0.6) (layers "B.Cu" "B.Paste" "B.Mask") (roundrect_rratio 0.25)
      (net 286 "/USB/USB1_TVS_N") (pintype "passive"))
  )
	(footprint "kria-k26-devboard-footprints:Nexperia_SOD128" (layer "B.Cu")
    (at 186.175 63.95 180)
    (property "Author" "Antmicro")
    (property "DNP" "DNP")
    (property "License" "Apache-2.0")
    (property "MPN" "PMEG3050EP,115")
    (property "Manufacturer" "Nexperia")
    (property "Sheetfile" "supply-oring.kicad_sch")
    (property "Sheetname" "Supply ORing")
    (property "dnp" "")
    (property "exclude_from_bom" "")
    (property "ki_description" "SCHOTTKY RECT 30V 5A, Vf=315 mV")
    (attr exclude_from_pos_files exclude_from_bom)
    (fp_text reference "D25" (at -1.015 1.78) (layer "B.SilkS")
        (effects (font (size 0.7 0.7) (thickness 0.15)) (justify left bottom mirror))
    )
    (fp_text value "PMEG3050EP,115" (at -4.37 -2.5) (layer "B.Fab") hide
        (effects (font (size 0.7 0.7) (thickness 0.15)) (justify left bottom mirror))
    )
    (fp_text user "Author: Antmicro" (at -4.37 -4.5) (layer "B.Fab") hide
        (effects (font (size 0.7 0.7) (thickness 0.15)) (justify left bottom mirror))
    )
    (fp_text user "${REFERENCE}" (at -4.37 -6.9) (layer "B.Fab") hide
        (effects (font (size 0.7 0.7) (thickness 0.15)) (justify left bottom mirror))
    )
    (fp_text user "License: Apache-2.0" (at -4.37 -5.7) (layer "B.Fab") hide
        (effects (font (size 0.7 0.7) (thickness 0.15)) (justify left bottom mirror))
    )
    (fp_line (start -2.121 -1.473) (end 2.12 -1.473)
      (stroke (width 0.15) (type solid)) (layer "B.SilkS"))
    (fp_line (start -2.121 -1.284) (end -2.121 -1.473)
      (stroke (width 0.15) (type solid)) (layer "B.SilkS"))
    (fp_line (start -2.121 1.474) (end -2.121 1.287)
      (stroke (width 0.15) (type solid)) (layer "B.SilkS"))
    (fp_line (start -1.6 1.4) (end -1.6 -1.4)
      (stroke (width 0.12) (type solid)) (layer "B.SilkS"))
    (fp_line (start 2.12 -1.473) (end 2.12 -1.284)
      (stroke (width 0.15) (type solid)) (layer "B.SilkS"))
    (fp_line (start 2.12 1.287) (end 2.12 1.474)
      (stroke (width 0.15) (type solid)) (layer "B.SilkS"))
    (fp_line (start 2.12 1.474) (end -2.121 1.474)
      (stroke (width 0.15) (type solid)) (layer "B.SilkS"))
    (fp_rect (start -2.8 1.6) (end 2.8 -1.6)
      (stroke (width 0.05) (type solid)) (fill none) (layer "B.CrtYd"))
    (fp_line (start -2.503 -0.952) (end -1.994 -0.952)
      (stroke (width 0.15) (type solid)) (layer "B.Fab"))
    (fp_line (start -2.503 0.954) (end -2.503 -0.952)
      (stroke (width 0.15) (type solid)) (layer "B.Fab"))
    (fp_line (start -1.994 -1.346) (end 1.993 -1.346)
      (stroke (width 0.15) (type solid)) (layer "B.Fab"))
    (fp_line (start -1.994 -0.952) (end -1.994 0.954)
      (stroke (width 0.15) (type solid)) (layer "B.Fab"))
    (fp_line (start -1.994 -0.673) (end -1.321 -1.346)
      (stroke (width 0.15) (type solid)) (layer "B.Fab"))
    (fp_line (start -1.994 0.675) (end -1.321 1.347)
      (stroke (width 0.15) (type solid)) (layer "B.Fab"))
    (fp_line (start -1.994 0.954) (end -2.503 0.954)
      (stroke (width 0.15) (type solid)) (layer "B.Fab"))
    (fp_line (start -1.994 1.347) (end -1.994 -1.346)
      (stroke (width 0.15) (type solid)) (layer "B.Fab"))
    (fp_line (start 1.993 -1.346) (end 1.993 1.347)
      (stroke (width 0.15) (type solid)) (layer "B.Fab"))
    (fp_line (start 1.993 -0.952) (end 2.5 -0.952)
      (stroke (width 0.15) (type solid)) (layer "B.Fab"))
    (fp_line (start 1.993 0.954) (end 1.993 -0.952)
      (stroke (width 0.15) (type solid)) (layer "B.Fab"))
    (fp_line (start 1.993 1.347) (end -1.994 1.347)
      (stroke (width 0.15) (type solid)) (layer "B.Fab"))
    (fp_line (start 2.5 -0.952) (end 2.5 0.954)
      (stroke (width 0.15) (type solid)) (layer "B.Fab"))
    (fp_line (start 2.5 0.954) (end 1.993 0.954)
      (stroke (width 0.15) (type solid)) (layer "B.Fab"))
    (pad "1" smd rect (at -2.298 0 180) (size 0.8096 1.905) (layers "B.Cu" "B.Paste" "B.Mask")
      (net 14 "/Power Supply/DC/DC conventers/DC_MAIN_BUS") (pinfunction "1") (pintype "passive"))
    (pad "2" smd rect (at 2.297 0 180) (size 0.8096 1.905) (layers "B.Cu" "B.Paste" "B.Mask")
      (net 22 "/Power Supply/DC Input/DC_IN") (pinfunction "2") (pintype "passive"))
  )
	(footprint "kria-k26-devboard-footprints:SOT-563" (layer "B.Cu")
    (at 115.72 74.21 90)
    (property "Author" "Antmicro")
    (property "License" "Apache-2.0")
    (property "MPN" "82400152")
    (property "Manufacturer" "Würth Elektronik")
    (property "Sheetfile" "usb.kicad_sch")
    (property "Sheetname" "USB")
    (property "ki_description" "TVS diode")
    (property "ki_keywords" "SMT, DIODE, IC, ESD, TVS")
    (attr smd)
    (fp_text reference "U27" (at -1.1 1.97 90) (layer "B.SilkS")
        (effects (font (size 0.7 0.7) (thickness 0.15)) (justify right bottom mirror))
    )
    (fp_text value "82400152" (at 0 -2 90) (layer "B.Fab") hide
        (effects (font (size 0.7 0.7) (thickness 0.15)) (justify right bottom mirror))
    )
    (fp_text user "${REFERENCE}" (at -1.299 -7.323 90) (layer "B.Fab") hide
        (effects (font (size 0.7 0.7) (thickness 0.15)) (justify right bottom mirror))
    )
    (fp_text user "License: Apache-2.0" (at -1.299 -4.924 90) (layer "B.Fab") hide
        (effects (font (size 0.7 0.7) (thickness 0.15)) (justify right bottom mirror))
    )
    (fp_text user "Author: Antmicro" (at -1.299 -6.124 90) (layer "B.Fab") hide
        (effects (font (size 0.7 0.7) (thickness 0.15)) (justify right bottom mirror))
    )
    (fp_line (start -0.778 -0.949) (end -0.424 -0.949)
      (stroke (width 0.15) (type solid)) (layer "B.SilkS"))
    (fp_line (start -0.778 -0.776) (end -0.778 -0.949)
      (stroke (width 0.15) (type solid)) (layer "B.SilkS"))
    (fp_line (start -0.499 0.974) (end -0.724 0.778)
      (stroke (width 0.15) (type solid)) (layer "B.SilkS"))
    (fp_line (start 0.776 -0.972) (end 0.526 -0.972)
      (stroke (width 0.15) (type solid)) (layer "B.SilkS"))
    (fp_line (start 0.776 -0.776) (end 0.776 -0.972)
      (stroke (width 0.15) (type solid)) (layer "B.SilkS"))
    (fp_line (start 0.776 0.974) (end 0.526 0.974)
      (stroke (width 0.15) (type solid)) (layer "B.SilkS"))
    (fp_line (start 0.776 0.974) (end 0.776 0.778)
      (stroke (width 0.15) (type solid)) (layer "B.SilkS"))
    (fp_circle (center -0.903 0.999) (end -0.952 0.95)
      (stroke (width 0.15) (type solid)) (fill solid) (layer "B.SilkS"))
    (fp_rect (start 1.19 1.12) (end -1.2 -1.1)
      (stroke (width 0.05) (type solid)) (fill none) (layer "B.CrtYd"))
    (fp_line (start -0.653 0.678) (end -0.653 -0.847)
      (stroke (width 0.15) (type solid)) (layer "B.Fab"))
    (fp_line (start -0.453 0.849) (end -0.653 0.678)
      (stroke (width 0.15) (type solid)) (layer "B.Fab"))
    (fp_line (start -0.453 0.849) (end 0.651 0.849)
      (stroke (width 0.15) (type solid)) (layer "B.Fab"))
    (fp_line (start 0.651 -0.847) (end -0.653 -0.847)
      (stroke (width 0.15) (type solid)) (layer "B.Fab"))
    (fp_line (start 0.651 0.849) (end 0.651 -0.847)
      (stroke (width 0.15) (type solid)) (layer "B.Fab"))
    (pad "1" smd roundrect (at -0.749 0.499 180) (size 0.3 0.6) (layers "B.Cu" "B.Paste" "B.Mask") (roundrect_rratio 0.25)
      (net 71 "/USB/USB3_N") (pintype "passive"))
    (pad "2" smd roundrect (at -0.749 -0.001 180) (size 0.3 0.6) (layers "B.Cu" "B.Paste" "B.Mask") (roundrect_rratio 0.25)
      (net 1 "GND") (pintype "passive"))
    (pad "3" smd roundrect (at -0.749 -0.497 180) (size 0.3 0.6) (layers "B.Cu" "B.Paste" "B.Mask") (roundrect_rratio 0.25)
      (net 72 "/USB/USB3_P") (pintype "passive"))
    (pad "4" smd roundrect (at 0.747 -0.497 180) (size 0.3 0.6) (layers "B.Cu" "B.Paste" "B.Mask") (roundrect_rratio 0.25)
      (net 291 "/USB/USB3_TVS_P") (pintype "passive"))
    (pad "5" smd roundrect (at 0.747 -0.001 180) (size 0.3 0.6) (layers "B.Cu" "B.Paste" "B.Mask") (roundrect_rratio 0.25)
      (net 86 "/USB/USB3_VBUS") (pintype "passive"))
    (pad "6" smd roundrect (at 0.747 0.499 180) (size 0.3 0.6) (layers "B.Cu" "B.Paste" "B.Mask") (roundrect_rratio 0.25)
      (net 290 "/USB/USB3_TVS_N") (pintype "passive"))
  )
	(footprint "kria-k26-devboard-footprints:C_0402_1005Metric" (layer "B.Cu")
    (at 134.225 122.050277 180)
    (descr "Capacitor SMD 0402")
    (tags "capacitor SMD 0402")
    (property "Author" "Antmicro")
    (property "Dielectric" "X5R")
    (property "License" "Apache-2.0")
    (property "MPN" "GRM155R61H104KE14D")
    (property "Manufacturer" "Murata")
    (property "Sheetfile" "pcie-m2-key-e.kicad_sch")
    (property "Sheetname" "PCIE M2 key E ")
    (property "Val" "100n")
    (property "Voltage" "50V")
    (property "ki_description" " ")
    (attr smd)
    (fp_text reference "C234" (at -3.785 -0.379724) (layer "B.SilkS")
        (effects (font (size 0.7 0.7) (thickness 0.15)) (justify left bottom mirror))
    )
    (fp_text value "C_100n_0402" (at 0 -1.4) (layer "B.Fab") hide
        (effects (font (size 0.7 0.7) (thickness 0.15)) (justify left bottom mirror))
    )
    (fp_text user "Author: Antmicro" (at -0.932 -4.17) (layer "B.Fab") hide
        (effects (font (size 0.7 0.7) (thickness 0.15)) (justify left bottom mirror))
    )
    (fp_text user "${REFERENCE}" (at -0.932 -3.168) (layer "B.Fab") hide
        (effects (font (size 0.7 0.7) (thickness 0.15)) (justify left bottom mirror))
    )
    (fp_text user "License: Apache-2.0" (at -0.932 -5.17) (layer "B.Fab") hide
        (effects (font (size 0.7 0.7) (thickness 0.15)) (justify left bottom mirror))
    )
    (fp_rect (start -0.94 0.47) (end 0.94 -0.47)
      (stroke (width 0.05) (type solid)) (fill none) (layer "B.CrtYd"))
    (fp_rect (start -0.499 0.249) (end 0.499 -0.249)
      (stroke (width 0.15) (type solid)) (fill none) (layer "B.Fab"))
    (pad "1" smd roundrect (at -0.484 0 180) (size 0.59 0.64) (layers "B.Cu" "B.Paste" "B.Mask") (roundrect_rratio 0.25)
      (net 90 "/PCIE M2 key E /GTR_DP3_M2C_N") (pintype "passive"))
    (pad "2" smd roundrect (at 0.484 0 180) (size 0.59 0.64) (layers "B.Cu" "B.Paste" "B.Mask") (roundrect_rratio 0.25)
      (net 91 "/PCIE M2 key E /GTR_DP3_M2C_C_N") (pintype "passive"))
  )
	(footprint "kria-k26-devboard-footprints:C_0402_1005Metric" (layer "B.Cu")
    (at 134.225 123.000276 180)
    (descr "Capacitor SMD 0402")
    (tags "capacitor SMD 0402")
    (property "Author" "Antmicro")
    (property "Dielectric" "X5R")
    (property "License" "Apache-2.0")
    (property "MPN" "GRM155R61H104KE14D")
    (property "Manufacturer" "Murata")
    (property "Sheetfile" "pcie-m2-key-e.kicad_sch")
    (property "Sheetname" "PCIE M2 key E ")
    (property "Val" "100n")
    (property "Voltage" "50V")
    (property "ki_description" " ")
    (attr smd)
    (fp_text reference "C233" (at -3.785 -0.379724) (layer "B.SilkS")
        (effects (font (size 0.7 0.7) (thickness 0.15)) (justify left bottom mirror))
    )
    (fp_text value "C_100n_0402" (at 0 -1.4) (layer "B.Fab") hide
        (effects (font (size 0.7 0.7) (thickness 0.15)) (justify left bottom mirror))
    )
    (fp_text user "Author: Antmicro" (at -0.932 -4.17) (layer "B.Fab") hide
        (effects (font (size 0.7 0.7) (thickness 0.15)) (justify left bottom mirror))
    )
    (fp_text user "${REFERENCE}" (at -0.932 -3.168) (layer "B.Fab") hide
        (effects (font (size 0.7 0.7) (thickness 0.15)) (justify left bottom mirror))
    )
    (fp_text user "License: Apache-2.0" (at -0.932 -5.17) (layer "B.Fab") hide
        (effects (font (size 0.7 0.7) (thickness 0.15)) (justify left bottom mirror))
    )
    (fp_rect (start -0.94 0.47) (end 0.94 -0.47)
      (stroke (width 0.05) (type solid)) (fill none) (layer "B.CrtYd"))
    (fp_rect (start -0.499 0.249) (end 0.499 -0.249)
      (stroke (width 0.15) (type solid)) (fill none) (layer "B.Fab"))
    (pad "1" smd roundrect (at -0.484 0 180) (size 0.59 0.64) (layers "B.Cu" "B.Paste" "B.Mask") (roundrect_rratio 0.25)
      (net 88 "/PCIE M2 key E /GTR_DP3_M2C_P") (pintype "passive"))
    (pad "2" smd roundrect (at 0.484 0 180) (size 0.59 0.64) (layers "B.Cu" "B.Paste" "B.Mask") (roundrect_rratio 0.25)
      (net 89 "/PCIE M2 key E /GTR_DP3_M2C_C_P") (pintype "passive"))
  )
)
